# S9S_MB_2U (Grand Teton) — schematic netlist excerpt (pin names and nets, part order shuffled) for the footprints in the layout excerpt that follows; sources: Cadence DE-HDL packaged netlist, KiCad conversion of 03242023_DA0F0TMBIJ0_F0T_Motherboard_J_brd_V01_OCP.brd

C945  Q_CAP_DIFFBUS  DIFF BUS_0.22UF 6.3V 20% X6S  pkg C0201  page 173 : \1\ = P5E_CPU0_PE2_TX_C_DP<10> ; \2\ = P5E_CPU0_PE2_TX_DP<10>
C1012  Q_CAP  22UF 4V 20% X6S  pkg C0402  page 74 : A = PVCCIN_CPU0 ; B = GND
R1418  Q_RES  2K 1% CHIP  pkg 0402LF  page 219 : A = RST_PCIE_CPU1_DEV_PERST_N ; B = GND

(kicad_pcb
	(version 20260206)
	(generator "pcbnew")
	(generator_version "10.0")
	(general
		(thickness 1.6)
		(legacy_teardrops no)
	)
	(paper "A4")
	(title_block
		(title "03242023_DA0F0TMBIJ0_F0T_Motherboard_J_brd_V01_OCP.brd")
		(comment 1 "Grand Teton / footprints 1903-1905 of 6105")
	)
	(layers
		(0 "F.Cu" signal "TOP")
		(4 "In1.Cu" signal "GND")
		(6 "In2.Cu" signal "IN1")
		(8 "In3.Cu" signal "GND1")
		(10 "In4.Cu" signal "IN2")
		(12 "In5.Cu" signal "GND2")
		(14 "In6.Cu" signal "IN3")
		(16 "In7.Cu" signal "GND3")
		(18 "In8.Cu" signal "VCC")
		(20 "In9.Cu" signal "VCC1")
		(22 "In10.Cu" signal "GND4")
		(24 "In11.Cu" signal "IN4")
		(26 "In12.Cu" signal "GND5")
		(28 "In13.Cu" signal "IN5")
		(30 "In14.Cu" signal "GND6")
		(32 "In15.Cu" signal "IN6")
		(34 "In16.Cu" signal "GND7")
		(2 "B.Cu" signal "BOTTOM")
		(9 "F.Adhes" user "F.Adhesive")
		(11 "B.Adhes" user "B.Adhesive")
		(13 "F.Paste" user "Package Geometry/Pastemask Top")
		(15 "B.Paste" user "Package Geometry/Pastemask Bottom")
		(5 "F.SilkS" user "Ref Des/Silkscreen Top")
		(7 "B.SilkS" user "Ref Des/Silkscreen Bottom")
		(1 "F.Mask" user "Board Geometry/Soldermask Top")
		(3 "B.Mask" user "Board Geometry/Soldermask Bottom")
		(17 "Dwgs.User" user "User.Drawings")
		(19 "Cmts.User" user "User.Comments")
		(21 "Eco1.User" user "User.Eco1")
		(23 "Eco2.User" user "User.Eco2")
		(25 "Edge.Cuts" user "Board Geometry/Outline")
		(27 "Margin" user)
		(31 "F.CrtYd" user "Package Geometry/Place Bound Top")
		(29 "B.CrtYd" user "Package Geometry/Place Bound Bottom")
		(35 "F.Fab" user "Ref Des/Assembly Top")
		(33 "B.Fab" user "Ref Des/Assembly Bottom")
	)
	(footprint ""
		(layer "F.Cu")
		(at 180.64988 -130.266948 90)
		(property "Reference" "R1418"
			(at 0 0 90)
			(layer "F.SilkS")
			(hide yes)
			(effects
				(font
					(size 1.27 1.27)
				)
			)
		)
		(property "Value" ""
			(at 0 0 90)
			(layer "F.Fab")
			(effects
				(font
					(size 1.27 1.27)
				)
			)
		)
		(duplicate_pad_numbers_are_jumpers no)
		(fp_line
			(start 0.7874 -0.4064)
			(end 0.7874 0.4064)
			(stroke
				(width 0.1524)
				(type default)
			)
			(layer "F.SilkS")
		)
		(fp_line
			(start -0.7874 -0.4064)
			(end 0.7874 -0.4064)
			(stroke
				(width 0.1524)
				(type default)
			)
			(layer "F.SilkS")
		)
		(fp_line
			(start 0.7874 0.4064)
			(end -0.7874 0.4064)
			(stroke
				(width 0.1524)
				(type default)
			)
			(layer "F.SilkS")
		)
		(fp_line
			(start -0.7874 0.4064)
			(end -0.7874 -0.4064)
			(stroke
				(width 0.1524)
				(type default)
			)
			(layer "F.SilkS")
		)
		(fp_line
			(start -0.12065 -0.305054)
			(end -0.12065 -0.2794)
			(stroke
				(width 0.1)
				(type default)
			)
			(layer "F.Fab")
		)
		(fp_line
			(start -0.67945 -0.305054)
			(end -0.12065 -0.305054)
			(stroke
				(width 0.1)
				(type default)
			)
			(layer "F.Fab")
		)
		(fp_line
			(start 0.67945 -0.3048)
			(end 0.67945 0.3048)
			(stroke
				(width 0.1)
				(type default)
			)
			(layer "F.Fab")
		)
		(fp_line
			(start 0.12065 -0.3048)
			(end 0.67945 -0.3048)
			(stroke
				(width 0.1)
				(type default)
			)
			(layer "F.Fab")
		)
		(fp_line
			(start 0.12065 -0.2794)
			(end 0.12065 -0.3048)
			(stroke
				(width 0.1)
				(type default)
			)
			(layer "F.Fab")
		)
		(fp_line
			(start -0.12065 -0.2794)
			(end 0.12065 -0.2794)
			(stroke
				(width 0.1)
				(type default)
			)
			(layer "F.Fab")
		)
		(fp_line
			(start 0.120396 0.2794)
			(end -0.12065 0.2794)
			(stroke
				(width 0.1)
				(type default)
			)
			(layer "F.Fab")
		)
		(fp_line
			(start -0.12065 0.2794)
			(end -0.12065 0.3048)
			(stroke
				(width 0.1)
				(type default)
			)
			(layer "F.Fab")
		)
		(fp_line
			(start 0.67945 0.3048)
			(end 0.120396 0.3048)
			(stroke
				(width 0.1)
				(type default)
			)
			(layer "F.Fab")
		)
		(fp_line
			(start 0.120396 0.3048)
			(end 0.120396 0.2794)
			(stroke
				(width 0.1)
				(type default)
			)
			(layer "F.Fab")
		)
		(fp_line
			(start -0.12065 0.3048)
			(end -0.67945 0.3048)
			(stroke
				(width 0.1)
				(type default)
			)
			(layer "F.Fab")
		)
		(fp_line
			(start -0.67945 0.3048)
			(end -0.67945 -0.305054)
			(stroke
				(width 0.1)
				(type default)
			)
			(layer "F.Fab")
		)
		(pad "1" smd circle
			(at -0.40005 0 90)
			(size 0 0)
			(layers "F.Cu" "F.Mask" "F.Paste")
			(net "RST_PCIE_CPU1_DEV_PERST_N")
		)
		(pad "2" smd circle
			(at 0.40005 0 90)
			(size 0 0)
			(layers "F.Cu" "F.Mask" "F.Paste")
			(net "GND")
		)
	)
	(footprint ""
		(layer "F.Cu")
		(at 367.44783 -255.053846 90)
		(property "Reference" "C1012"
			(at 0 0 90)
			(layer "F.SilkS")
			(hide yes)
			(effects
				(font
					(size 1.27 1.27)
				)
			)
		)
		(property "Value" ""
			(at 0 0 90)
			(layer "F.Fab")
			(effects
				(font
					(size 1.27 1.27)
				)
			)
		)
		(duplicate_pad_numbers_are_jumpers no)
		(fp_line
			(start 0.7874 -0.4064)
			(end 0.7874 0.4064)
			(stroke
				(width 0.1524)
				(type default)
			)
			(layer "F.SilkS")
		)
		(fp_line
			(start -0.7874 -0.4064)
			(end 0.7874 -0.4064)
			(stroke
				(width 0.1524)
				(type default)
			)
			(layer "F.SilkS")
		)
		(fp_line
			(start 0.7874 0.4064)
			(end -0.7874 0.4064)
			(stroke
				(width 0.1524)
				(type default)
			)
			(layer "F.SilkS")
		)
		(fp_line
			(start -0.7874 0.4064)
			(end -0.7874 -0.4064)
			(stroke
				(width 0.1524)
				(type default)
			)
			(layer "F.SilkS")
		)
		(fp_line
			(start -0.12065 -0.305054)
			(end -0.12065 -0.2794)
			(stroke
				(width 0.1)
				(type default)
			)
			(layer "F.Fab")
		)
		(fp_line
			(start -0.67945 -0.305054)
			(end -0.12065 -0.305054)
			(stroke
				(width 0.1)
				(type default)
			)
			(layer "F.Fab")
		)
		(fp_line
			(start 0.67945 -0.3048)
			(end 0.67945 0.3048)
			(stroke
				(width 0.1)
				(type default)
			)
			(layer "F.Fab")
		)
		(fp_line
			(start 0.12065 -0.3048)
			(end 0.67945 -0.3048)
			(stroke
				(width 0.1)
				(type default)
			)
			(layer "F.Fab")
		)
		(fp_line
			(start 0.12065 -0.2794)
			(end 0.12065 -0.3048)
			(stroke
				(width 0.1)
				(type default)
			)
			(layer "F.Fab")
		)
		(fp_line
			(start -0.12065 -0.2794)
			(end 0.12065 -0.2794)
			(stroke
				(width 0.1)
				(type default)
			)
			(layer "F.Fab")
		)
		(fp_line
			(start 0.120396 0.2794)
			(end -0.12065 0.2794)
			(stroke
				(width 0.1)
				(type default)
			)
			(layer "F.Fab")
		)
		(fp_line
			(start -0.12065 0.2794)
			(end -0.12065 0.3048)
			(stroke
				(width 0.1)
				(type default)
			)
			(layer "F.Fab")
		)
		(fp_line
			(start 0.67945 0.3048)
			(end 0.120396 0.3048)
			(stroke
				(width 0.1)
				(type default)
			)
			(layer "F.Fab")
		)
		(fp_line
			(start 0.120396 0.3048)
			(end 0.120396 0.2794)
			(stroke
				(width 0.1)
				(type default)
			)
			(layer "F.Fab")
		)
		(fp_line
			(start -0.12065 0.3048)
			(end -0.67945 0.3048)
			(stroke
				(width 0.1)
				(type default)
			)
			(layer "F.Fab")
		)
		(fp_line
			(start -0.67945 0.3048)
			(end -0.67945 -0.305054)
			(stroke
				(width 0.1)
				(type default)
			)
			(layer "F.Fab")
		)
		(pad "1" smd circle
			(at -0.40005 0 90)
			(size 0 0)
			(layers "F.Cu" "F.Mask" "F.Paste")
			(net "PVCCIN_CPU0")
		)
		(pad "2" smd circle
			(at 0.40005 0 90)
			(size 0 0)
			(layers "F.Cu" "F.Mask" "F.Paste")
			(net "GND")
		)
	)
	(footprint ""
		(layer "F.Cu")
		(at 386.71373 -402.371052 -90)
		(property "Reference" "C945"
			(at 0 0 270)
			(layer "F.SilkS")
			(hide yes)
			(effects
				(font
					(size 1.27 1.27)
				)
			)
		)
		(property "Value" ""
			(at 0 0 270)
			(layer "F.Fab")
			(effects
				(font
					(size 1.27 1.27)
				)
			)
		)
		(duplicate_pad_numbers_are_jumpers no)
		(fp_line
			(start -0.299974 0.150114)
			(end -0.299974 -0.150114)
			(stroke
				(width 0.1)
				(type default)
			)
			(layer "F.Fab")
		)
		(fp_line
			(start 0.299974 0.150114)
			(end -0.299974 0.150114)
			(stroke
				(width 0.1)
				(type default)
			)
			(layer "F.Fab")
		)
		(fp_line
			(start -0.299974 -0.150114)
			(end 0.299974 -0.150114)
			(stroke
				(width 0.1)
				(type default)
			)
			(layer "F.Fab")
		)
		(fp_line
			(start 0.299974 -0.150114)
			(end 0.299974 0.150114)
			(stroke
				(width 0.1)
				(type default)
			)
			(layer "F.Fab")
		)
		(pad "1" smd rect
			(at -0.2667 0 270)
			(size 0.3048 0.381)
			(layers "F.Cu" "F.Mask" "F.Paste")
			(net "P5E_CPU0_PE2_TX_C_DP<10>")
		)
		(pad "2" smd rect
			(at 0.2667 0 270)
			(size 0.3048 0.381)
			(layers "F.Cu" "F.Mask" "F.Paste")
			(net "P5E_CPU0_PE2_TX_DP<10>")
		)
	)
)
